(kicad_pcb
	(version 20260206)
	(generator "pcbnew")
	(generator_version "10.0")
	(general
		(thickness 1.6)
		(legacy_teardrops no)
	)
	(paper "A4")
	(title_block
		(title "03242023_DA0F0TMBIJ0_F0T_Motherboard_J_brd_V01_OCP.brd")
		(comment 1 "Grand Teton / footprints 3505-3510 of 6105")
	)
	(layers
		(0 "F.Cu" signal "TOP")
		(4 "In1.Cu" signal "GND")
		(6 "In2.Cu" signal "IN1")
		(8 "In3.Cu" signal "GND1")
		(10 "In4.Cu" signal "IN2")
		(12 "In5.Cu" signal "GND2")
		(14 "In6.Cu" signal "IN3")
		(16 "In7.Cu" signal "GND3")
		(18 "In8.Cu" signal "VCC")
		(20 "In9.Cu" signal "VCC1")
		(22 "In10.Cu" signal "GND4")
		(24 "In11.Cu" signal "IN4")
		(26 "In12.Cu" signal "GND5")
		(28 "In13.Cu" signal "IN5")
		(30 "In14.Cu" signal "GND6")
		(32 "In15.Cu" signal "IN6")
		(34 "In16.Cu" signal "GND7")
		(2 "B.Cu" signal "BOTTOM")
		(9 "F.Adhes" user "F.Adhesive")
		(11 "B.Adhes" user "B.Adhesive")
		(13 "F.Paste" user "Package Geometry/Pastemask Top")
		(15 "B.Paste" user "Package Geometry/Pastemask Bottom")
		(5 "F.SilkS" user "Ref Des/Silkscreen Top")
		(7 "B.SilkS" user "Ref Des/Silkscreen Bottom")
		(1 "F.Mask" user "Board Geometry/Soldermask Top")
		(3 "B.Mask" user "Board Geometry/Soldermask Bottom")
		(17 "Dwgs.User" user "User.Drawings")
		(19 "Cmts.User" user "User.Comments")
		(21 "Eco1.User" user "User.Eco1")
		(23 "Eco2.User" user "User.Eco2")
		(25 "Edge.Cuts" user "Board Geometry/Outline")
		(27 "Margin" user)
		(31 "F.CrtYd" user "Package Geometry/Place Bound Top")
		(29 "B.CrtYd" user "Package Geometry/Place Bound Bottom")
		(35 "F.Fab" user "Ref Des/Assembly Top")
		(33 "B.Fab" user "Ref Des/Assembly Bottom")
	)
	(footprint ""
		(layer "F.Cu")
		(at 22.809454 -107.777026 180)
		(property "Reference" "R3670"
			(at 0 0 180)
			(layer "F.SilkS")
			(hide yes)
			(effects
				(font
					(size 1.27 1.27)
				)
			)
		)
		(property "Value" ""
			(at 0 0 180)
			(layer "F.Fab")
			(effects
				(font
					(size 1.27 1.27)
				)
			)
		)
		(duplicate_pad_numbers_are_jumpers no)
		(fp_line
			(start 0.7874 0.4064)
			(end -0.7874 0.4064)
			(stroke
				(width 0.1524)
				(type default)
			)
			(layer "F.SilkS")
		)
		(fp_line
			(start 0.7874 -0.4064)
			(end 0.7874 0.4064)
			(stroke
				(width 0.1524)
				(type default)
			)
			(layer "F.SilkS")
		)
		(fp_line
			(start -0.7874 0.4064)
			(end -0.7874 -0.4064)
			(stroke
				(width 0.1524)
				(type default)
			)
			(layer "F.SilkS")
		)
		(fp_line
			(start -0.7874 -0.4064)
			(end 0.7874 -0.4064)
			(stroke
				(width 0.1524)
				(type default)
			)
			(layer "F.SilkS")
		)
		(fp_line
			(start 0.67945 0.3048)
			(end 0.120396 0.3048)
			(stroke
				(width 0.1)
				(type default)
			)
			(layer "F.Fab")
		)
		(fp_line
			(start 0.67945 -0.3048)
			(end 0.67945 0.3048)
			(stroke
				(width 0.1)
				(type default)
			)
			(layer "F.Fab")
		)
		(fp_line
			(start 0.12065 -0.2794)
			(end 0.12065 -0.3048)
			(stroke
				(width 0.1)
				(type default)
			)
			(layer "F.Fab")
		)
		(fp_line
			(start 0.12065 -0.3048)
			(end 0.67945 -0.3048)
			(stroke
				(width 0.1)
				(type default)
			)
			(layer "F.Fab")
		)
		(fp_line
			(start 0.120396 0.3048)
			(end 0.120396 0.2794)
			(stroke
				(width 0.1)
				(type default)
			)
			(layer "F.Fab")
		)
		(fp_line
			(start 0.120396 0.2794)
			(end -0.12065 0.2794)
			(stroke
				(width 0.1)
				(type default)
			)
			(layer "F.Fab")
		)
		(fp_line
			(start -0.12065 0.3048)
			(end -0.67945 0.3048)
			(stroke
				(width 0.1)
				(type default)
			)
			(layer "F.Fab")
		)
		(fp_line
			(start -0.12065 0.2794)
			(end -0.12065 0.3048)
			(stroke
				(width 0.1)
				(type default)
			)
			(layer "F.Fab")
		)
		(fp_line
			(start -0.12065 -0.2794)
			(end 0.12065 -0.2794)
			(stroke
				(width 0.1)
				(type default)
			)
			(layer "F.Fab")
		)
		(fp_line
			(start -0.12065 -0.305054)
			(end -0.12065 -0.2794)
			(stroke
				(width 0.1)
				(type default)
			)
			(layer "F.Fab")
		)
		(fp_line
			(start -0.67945 0.3048)
			(end -0.67945 -0.305054)
			(stroke
				(width 0.1)
				(type default)
			)
			(layer "F.Fab")
		)
		(fp_line
			(start -0.67945 -0.305054)
			(end -0.12065 -0.305054)
			(stroke
				(width 0.1)
				(type default)
			)
			(layer "F.Fab")
		)
		(pad "1" smd circle
			(at -0.40005 0 180)
			(size 0 0)
			(layers "F.Cu" "F.Mask" "F.Paste")
			(net "ADC128_A0")
		)
		(pad "2" smd circle
			(at 0.40005 0 180)
			(size 0 0)
			(layers "F.Cu" "F.Mask" "F.Paste")
			(net "GND")
		)
	)
	(footprint ""
		(layer "F.Cu")
		(at 258.18338 -92.258388 180)
		(property "Reference" "R3640"
			(at 0 0 180)
			(layer "F.SilkS")
			(hide yes)
			(effects
				(font
					(size 1.27 1.27)
				)
			)
		)
		(property "Value" ""
			(at 0 0 180)
			(layer "F.Fab")
			(effects
				(font
					(size 1.27 1.27)
				)
			)
		)
		(duplicate_pad_numbers_are_jumpers no)
		(fp_line
			(start 0.7874 0.4064)
			(end -0.7874 0.4064)
			(stroke
				(width 0.1524)
				(type default)
			)
			(layer "F.SilkS")
		)
		(fp_line
			(start 0.7874 -0.4064)
			(end 0.7874 0.4064)
			(stroke
				(width 0.1524)
				(type default)
			)
			(layer "F.SilkS")
		)
		(fp_line
			(start -0.7874 0.4064)
			(end -0.7874 -0.4064)
			(stroke
				(width 0.1524)
				(type default)
			)
			(layer "F.SilkS")
		)
		(fp_line
			(start -0.7874 -0.4064)
			(end 0.7874 -0.4064)
			(stroke
				(width 0.1524)
				(type default)
			)
			(layer "F.SilkS")
		)
		(fp_line
			(start 0.67945 0.3048)
			(end 0.120396 0.3048)
			(stroke
				(width 0.1)
				(type default)
			)
			(layer "F.Fab")
		)
		(fp_line
			(start 0.67945 -0.3048)
			(end 0.67945 0.3048)
			(stroke
				(width 0.1)
				(type default)
			)
			(layer "F.Fab")
		)
		(fp_line
			(start 0.12065 -0.2794)
			(end 0.12065 -0.3048)
			(stroke
				(width 0.1)
				(type default)
			)
			(layer "F.Fab")
		)
		(fp_line
			(start 0.12065 -0.3048)
			(end 0.67945 -0.3048)
			(stroke
				(width 0.1)
				(type default)
			)
			(layer "F.Fab")
		)
		(fp_line
			(start 0.120396 0.3048)
			(end 0.120396 0.2794)
			(stroke
				(width 0.1)
				(type default)
			)
			(layer "F.Fab")
		)
		(fp_line
			(start 0.120396 0.2794)
			(end -0.12065 0.2794)
			(stroke
				(width 0.1)
				(type default)
			)
			(layer "F.Fab")
		)
		(fp_line
			(start -0.12065 0.3048)
			(end -0.67945 0.3048)
			(stroke
				(width 0.1)
				(type default)
			)
			(layer "F.Fab")
		)
		(fp_line
			(start -0.12065 0.2794)
			(end -0.12065 0.3048)
			(stroke
				(width 0.1)
				(type default)
			)
			(layer "F.Fab")
		)
		(fp_line
			(start -0.12065 -0.2794)
			(end 0.12065 -0.2794)
			(stroke
				(width 0.1)
				(type default)
			)
			(layer "F.Fab")
		)
		(fp_line
			(start -0.12065 -0.305054)
			(end -0.12065 -0.2794)
			(stroke
				(width 0.1)
				(type default)
			)
			(layer "F.Fab")
		)
		(fp_line
			(start -0.67945 0.3048)
			(end -0.67945 -0.305054)
			(stroke
				(width 0.1)
				(type default)
			)
			(layer "F.Fab")
		)
		(fp_line
			(start -0.67945 -0.305054)
			(end -0.12065 -0.305054)
			(stroke
				(width 0.1)
				(type default)
			)
			(layer "F.Fab")
		)
		(pad "1" smd circle
			(at -0.40005 0 180)
			(size 0 0)
			(layers "F.Cu" "F.Mask" "F.Paste")
			(net "P3V3_AUX")
		)
		(pad "2" smd circle
			(at 0.40005 0 180)
			(size 0 0)
			(layers "F.Cu" "F.Mask" "F.Paste")
			(net "CK440Q_OE_3")
		)
	)
	(footprint ""
		(layer "F.Cu")
		(at 46.085506 -395.699996)
		(property "Reference" "R4651"
			(at 0 0 0)
			(layer "F.SilkS")
			(hide yes)
			(effects
				(font
					(size 1.27 1.27)
				)
			)
		)
		(property "Value" ""
			(at 0 0 0)
			(layer "F.Fab")
			(effects
				(font
					(size 1.27 1.27)
				)
			)
		)
		(duplicate_pad_numbers_are_jumpers no)
		(fp_line
			(start -0.7874 -0.4064)
			(end 0.7874 -0.4064)
			(stroke
				(width 0.1524)
				(type default)
			)
			(layer "F.SilkS")
		)
		(fp_line
			(start -0.7874 0.4064)
			(end -0.7874 -0.4064)
			(stroke
				(width 0.1524)
				(type default)
			)
			(layer "F.SilkS")
		)
		(fp_line
			(start 0.7874 -0.4064)
			(end 0.7874 0.4064)
			(stroke
				(width 0.1524)
				(type default)
			)
			(layer "F.SilkS")
		)
		(fp_line
			(start 0.7874 0.4064)
			(end -0.7874 0.4064)
			(stroke
				(width 0.1524)
				(type default)
			)
			(layer "F.SilkS")
		)
		(fp_line
			(start -0.67945 -0.305054)
			(end -0.12065 -0.305054)
			(stroke
				(width 0.1)
				(type default)
			)
			(layer "F.Fab")
		)
		(fp_line
			(start -0.67945 0.3048)
			(end -0.67945 -0.305054)
			(stroke
				(width 0.1)
				(type default)
			)
			(layer "F.Fab")
		)
		(fp_line
			(start -0.12065 -0.305054)
			(end -0.12065 -0.2794)
			(stroke
				(width 0.1)
				(type default)
			)
			(layer "F.Fab")
		)
		(fp_line
			(start -0.12065 -0.2794)
			(end 0.12065 -0.2794)
			(stroke
				(width 0.1)
				(type default)
			)
			(layer "F.Fab")
		)
		(fp_line
			(start -0.12065 0.2794)
			(end -0.12065 0.3048)
			(stroke
				(width 0.1)
				(type default)
			)
			(layer "F.Fab")
		)
		(fp_line
			(start -0.12065 0.3048)
			(end -0.67945 0.3048)
			(stroke
				(width 0.1)
				(type default)
			)
			(layer "F.Fab")
		)
		(fp_line
			(start 0.120396 0.2794)
			(end -0.12065 0.2794)
			(stroke
				(width 0.1)
				(type default)
			)
			(layer "F.Fab")
		)
		(fp_line
			(start 0.120396 0.3048)
			(end 0.120396 0.2794)
			(stroke
				(width 0.1)
				(type default)
			)
			(layer "F.Fab")
		)
		(fp_line
			(start 0.12065 -0.3048)
			(end 0.67945 -0.3048)
			(stroke
				(width 0.1)
				(type default)
			)
			(layer "F.Fab")
		)
		(fp_line
			(start 0.12065 -0.2794)
			(end 0.12065 -0.3048)
			(stroke
				(width 0.1)
				(type default)
			)
			(layer "F.Fab")
		)
		(fp_line
			(start 0.67945 -0.3048)
			(end 0.67945 0.3048)
			(stroke
				(width 0.1)
				(type default)
			)
			(layer "F.Fab")
		)
		(fp_line
			(start 0.67945 0.3048)
			(end 0.120396 0.3048)
			(stroke
				(width 0.1)
				(type default)
			)
			(layer "F.Fab")
		)
		(pad "1" smd circle
			(at -0.40005 0)
			(size 0 0)
			(layers "F.Cu" "F.Mask" "F.Paste")
			(net "FM_P2E_EN2_N")
		)
		(pad "2" smd circle
			(at 0.40005 0)
			(size 0 0)
			(layers "F.Cu" "F.Mask" "F.Paste")
			(net "CLK_GEN2_GPU_FPGA_OE_OR_N")
		)
	)
	(footprint ""
		(layer "F.Cu")
		(at 308.96687 -428.9298)
		(property "Reference" "R4572"
			(at 0 0 0)
			(layer "F.SilkS")
			(hide yes)
			(effects
				(font
					(size 1.27 1.27)
				)
			)
		)
		(property "Value" ""
			(at 0 0 0)
			(layer "F.Fab")
			(effects
				(font
					(size 1.27 1.27)
				)
			)
		)
		(duplicate_pad_numbers_are_jumpers no)
		(fp_line
			(start -0.7874 -0.4064)
			(end 0.7874 -0.4064)
			(stroke
				(width 0.1524)
				(type default)
			)
			(layer "F.SilkS")
		)
		(fp_line
			(start -0.7874 0.4064)
			(end -0.7874 -0.4064)
			(stroke
				(width 0.1524)
				(type default)
			)
			(layer "F.SilkS")
		)
		(fp_line
			(start 0.7874 -0.4064)
			(end 0.7874 0.4064)
			(stroke
				(width 0.1524)
				(type default)
			)
			(layer "F.SilkS")
		)
		(fp_line
			(start 0.7874 0.4064)
			(end -0.7874 0.4064)
			(stroke
				(width 0.1524)
				(type default)
			)
			(layer "F.SilkS")
		)
		(fp_line
			(start -0.67945 -0.305054)
			(end -0.12065 -0.305054)
			(stroke
				(width 0.1)
				(type default)
			)
			(layer "F.Fab")
		)
		(fp_line
			(start -0.67945 0.3048)
			(end -0.67945 -0.305054)
			(stroke
				(width 0.1)
				(type default)
			)
			(layer "F.Fab")
		)
		(fp_line
			(start -0.12065 -0.305054)
			(end -0.12065 -0.2794)
			(stroke
				(width 0.1)
				(type default)
			)
			(layer "F.Fab")
		)
		(fp_line
			(start -0.12065 -0.2794)
			(end 0.12065 -0.2794)
			(stroke
				(width 0.1)
				(type default)
			)
			(layer "F.Fab")
		)
		(fp_line
			(start -0.12065 0.2794)
			(end -0.12065 0.3048)
			(stroke
				(width 0.1)
				(type default)
			)
			(layer "F.Fab")
		)
		(fp_line
			(start -0.12065 0.3048)
			(end -0.67945 0.3048)
			(stroke
				(width 0.1)
				(type default)
			)
			(layer "F.Fab")
		)
		(fp_line
			(start 0.120396 0.2794)
			(end -0.12065 0.2794)
			(stroke
				(width 0.1)
				(type default)
			)
			(layer "F.Fab")
		)
		(fp_line
			(start 0.120396 0.3048)
			(end 0.120396 0.2794)
			(stroke
				(width 0.1)
				(type default)
			)
			(layer "F.Fab")
		)
		(fp_line
			(start 0.12065 -0.3048)
			(end 0.67945 -0.3048)
			(stroke
				(width 0.1)
				(type default)
			)
			(layer "F.Fab")
		)
		(fp_line
			(start 0.12065 -0.2794)
			(end 0.12065 -0.3048)
			(stroke
				(width 0.1)
				(type default)
			)
			(layer "F.Fab")
		)
		(fp_line
			(start 0.67945 -0.3048)
			(end 0.67945 0.3048)
			(stroke
				(width 0.1)
				(type default)
			)
			(layer "F.Fab")
		)
		(fp_line
			(start 0.67945 0.3048)
			(end 0.120396 0.3048)
			(stroke
				(width 0.1)
				(type default)
			)
			(layer "F.Fab")
		)
		(pad "1" smd circle
			(at -0.40005 0)
			(size 0 0)
			(layers "F.Cu" "F.Mask" "F.Paste")
			(net "GPU_3V3IO_RSVD1_FFU")
		)
		(pad "2" smd circle
			(at 0.40005 0)
			(size 0 0)
			(layers "F.Cu" "F.Mask" "F.Paste")
			(net "GPU_3V3IO_RSVD1_FFU_ISO")
		)
	)
	(footprint ""
		(layer "F.Cu")
		(at 114.557556 -355.340666 -90)
		(property "Reference" "PR242"
			(at 0 0 270)
			(layer "F.SilkS")
			(hide yes)
			(effects
				(font
					(size 1.27 1.27)
				)
			)
		)
		(property "Value" ""
			(at 0 0 270)
			(layer "F.Fab")
			(effects
				(font
					(size 1.27 1.27)
				)
			)
		)
		(duplicate_pad_numbers_are_jumpers no)
		(fp_line
			(start -0.7874 0.4064)
			(end -0.7874 -0.4064)
			(stroke
				(width 0.1524)
				(type default)
			)
			(layer "F.SilkS")
		)
		(fp_line
			(start 0.7874 0.4064)
			(end -0.7874 0.4064)
			(stroke
				(width 0.1524)
				(type default)
			)
			(layer "F.SilkS")
		)
		(fp_line
			(start -0.7874 -0.4064)
			(end 0.7874 -0.4064)
			(stroke
				(width 0.1524)
				(type default)
			)
			(layer "F.SilkS")
		)
		(fp_line
			(start 0.7874 -0.4064)
			(end 0.7874 0.4064)
			(stroke
				(width 0.1524)
				(type default)
			)
			(layer "F.SilkS")
		)
		(fp_line
			(start -0.67945 0.3048)
			(end -0.67945 -0.305054)
			(stroke
				(width 0.1)
				(type default)
			)
			(layer "F.Fab")
		)
		(fp_line
			(start -0.12065 0.3048)
			(end -0.67945 0.3048)
			(stroke
				(width 0.1)
				(type default)
			)
			(layer "F.Fab")
		)
		(fp_line
			(start 0.120396 0.3048)
			(end 0.120396 0.2794)
			(stroke
				(width 0.1)
				(type default)
			)
			(layer "F.Fab")
		)
		(fp_line
			(start 0.67945 0.3048)
			(end 0.120396 0.3048)
			(stroke
				(width 0.1)
				(type default)
			)
			(layer "F.Fab")
		)
		(fp_line
			(start -0.12065 0.2794)
			(end -0.12065 0.3048)
			(stroke
				(width 0.1)
				(type default)
			)
			(layer "F.Fab")
		)
		(fp_line
			(start 0.120396 0.2794)
			(end -0.12065 0.2794)
			(stroke
				(width 0.1)
				(type default)
			)
			(layer "F.Fab")
		)
		(fp_line
			(start -0.12065 -0.2794)
			(end 0.12065 -0.2794)
			(stroke
				(width 0.1)
				(type default)
			)
			(layer "F.Fab")
		)
		(fp_line
			(start 0.12065 -0.2794)
			(end 0.12065 -0.3048)
			(stroke
				(width 0.1)
				(type default)
			)
			(layer "F.Fab")
		)
		(fp_line
			(start 0.12065 -0.3048)
			(end 0.67945 -0.3048)
			(stroke
				(width 0.1)
				(type default)
			)
			(layer "F.Fab")
		)
		(fp_line
			(start 0.67945 -0.3048)
			(end 0.67945 0.3048)
			(stroke
				(width 0.1)
				(type default)
			)
			(layer "F.Fab")
		)
		(fp_line
			(start -0.67945 -0.305054)
			(end -0.12065 -0.305054)
			(stroke
				(width 0.1)
				(type default)
			)
			(layer "F.Fab")
		)
		(fp_line
			(start -0.12065 -0.305054)
			(end -0.12065 -0.2794)
			(stroke
				(width 0.1)
				(type default)
			)
			(layer "F.Fab")
		)
		(pad "1" smd circle
			(at -0.40005 0 270)
			(size 0 0)
			(layers "F.Cu" "F.Mask" "F.Paste")
			(net "SH_PVCCFA_EHV_FIVRA_CPU1")
		)
		(pad "2" smd circle
			(at 0.40005 0 270)
			(size 0 0)
			(layers "F.Cu" "F.Mask" "F.Paste")
			(net "SH_PVCCFA_EHV_FIVRA_CPU1_R")
		)
	)
	(footprint ""
		(layer "F.Cu")
		(at 303.543208 -369.067588)
		(property "Reference" "PC1670"
			(at 0 0 0)
			(layer "F.SilkS")
			(hide yes)
			(effects
				(font
					(size 1.27 1.27)
				)
			)
		)
		(property "Value" ""
			(at 0 0 0)
			(layer "F.Fab")
			(effects
				(font
					(size 1.27 1.27)
				)
			)
		)
		(duplicate_pad_numbers_are_jumpers no)
		(fp_line
			(start -1.524 -0.762)
			(end 1.524 -0.762)
			(stroke
				(width 0.1524)
				(type default)
			)
			(layer "F.SilkS")
		)
		(fp_line
			(start -1.524 0.762)
			(end -1.524 -0.762)
			(stroke
				(width 0.1524)
				(type default)
			)
			(layer "F.SilkS")
		)
		(fp_line
			(start 1.524 -0.762)
			(end 1.524 0.762)
			(stroke
				(width 0.1524)
				(type default)
			)
			(layer "F.SilkS")
		)
		(fp_line
			(start 1.524 0.762)
			(end -1.524 0.762)
			(stroke
				(width 0.1524)
				(type default)
			)
			(layer "F.SilkS")
		)
		(fp_line
			(start -1.1049 -0.724916)
			(end -1.1049 0.724916)
			(stroke
				(width 0.1)
				(type default)
			)
			(layer "F.Fab")
		)
		(fp_line
			(start -1.1049 0.724916)
			(end 1.1049 0.724916)
			(stroke
				(width 0.1)
				(type default)
			)
			(layer "F.Fab")
		)
		(fp_line
			(start 1.1049 -0.724916)
			(end -1.1049 -0.724916)
			(stroke
				(width 0.1)
				(type default)
			)
			(layer "F.Fab")
		)
		(fp_line
			(start 1.1049 0.724916)
			(end 1.1049 -0.724916)
			(stroke
				(width 0.1)
				(type default)
			)
			(layer "F.Fab")
		)
		(pad "1" smd rect
			(at -0.889 0 180)
			(size 1.016 1.27)
			(layers "F.Cu" "F.Mask" "F.Paste")
			(net "SW_P12V_PVCCFA_EHV_FIVRA_CPU0_L")
		)
		(pad "2" smd rect
			(at 0.889 0 180)
			(size 1.016 1.27)
			(layers "F.Cu" "F.Mask" "F.Paste")
			(net "GND")
		)
	)
)
